(kicad_pcb
	(version 20260206)
	(generator "pcbnew")
	(generator_version "10.0")
	(general
		(thickness 1.6)
		(legacy_teardrops no)
	)
	(paper "A4")
	(title_block
		(title "03242023_DA0F0TMBIJ0_F0T_Motherboard_J_brd_V01_OCP.brd")
		(comment 1 "Grand Teton / footprints 1723-1729 of 6105")
	)
	(layers
		(0 "F.Cu" signal "TOP")
		(4 "In1.Cu" signal "GND")
		(6 "In2.Cu" signal "IN1")
		(8 "In3.Cu" signal "GND1")
		(10 "In4.Cu" signal "IN2")
		(12 "In5.Cu" signal "GND2")
		(14 "In6.Cu" signal "IN3")
		(16 "In7.Cu" signal "GND3")
		(18 "In8.Cu" signal "VCC")
		(20 "In9.Cu" signal "VCC1")
		(22 "In10.Cu" signal "GND4")
		(24 "In11.Cu" signal "IN4")
		(26 "In12.Cu" signal "GND5")
		(28 "In13.Cu" signal "IN5")
		(30 "In14.Cu" signal "GND6")
		(32 "In15.Cu" signal "IN6")
		(34 "In16.Cu" signal "GND7")
		(2 "B.Cu" signal "BOTTOM")
		(9 "F.Adhes" user "F.Adhesive")
		(11 "B.Adhes" user "B.Adhesive")
		(13 "F.Paste" user "Package Geometry/Pastemask Top")
		(15 "B.Paste" user "Package Geometry/Pastemask Bottom")
		(5 "F.SilkS" user "Ref Des/Silkscreen Top")
		(7 "B.SilkS" user "Ref Des/Silkscreen Bottom")
		(1 "F.Mask" user "Board Geometry/Soldermask Top")
		(3 "B.Mask" user "Board Geometry/Soldermask Bottom")
		(17 "Dwgs.User" user "User.Drawings")
		(19 "Cmts.User" user "User.Comments")
		(21 "Eco1.User" user "User.Eco1")
		(23 "Eco2.User" user "User.Eco2")
		(25 "Edge.Cuts" user "Board Geometry/Outline")
		(27 "Margin" user)
		(31 "F.CrtYd" user "Package Geometry/Place Bound Top")
		(29 "B.CrtYd" user "Package Geometry/Place Bound Bottom")
		(35 "F.Fab" user "Ref Des/Assembly Top")
		(33 "B.Fab" user "Ref Des/Assembly Bottom")
	)
	(footprint ""
		(layer "F.Cu")
		(at 390.587484 -331.449172 90)
		(property "Reference" "PC242_P0_8"
			(at 0 0 90)
			(layer "F.SilkS")
			(hide yes)
			(effects
				(font
					(size 1.27 1.27)
				)
			)
		)
		(property "Value" ""
			(at 0 0 90)
			(layer "F.Fab")
			(effects
				(font
					(size 1.27 1.27)
				)
			)
		)
		(duplicate_pad_numbers_are_jumpers no)
		(fp_line
			(start 0.7874 -0.4064)
			(end 0.7874 0.4064)
			(stroke
				(width 0.1524)
				(type default)
			)
			(layer "F.SilkS")
		)
		(fp_line
			(start -0.7874 -0.4064)
			(end 0.7874 -0.4064)
			(stroke
				(width 0.1524)
				(type default)
			)
			(layer "F.SilkS")
		)
		(fp_line
			(start 0.7874 0.4064)
			(end -0.7874 0.4064)
			(stroke
				(width 0.1524)
				(type default)
			)
			(layer "F.SilkS")
		)
		(fp_line
			(start -0.7874 0.4064)
			(end -0.7874 -0.4064)
			(stroke
				(width 0.1524)
				(type default)
			)
			(layer "F.SilkS")
		)
		(fp_line
			(start -0.12065 -0.305054)
			(end -0.12065 -0.2794)
			(stroke
				(width 0.1)
				(type default)
			)
			(layer "F.Fab")
		)
		(fp_line
			(start -0.67945 -0.305054)
			(end -0.12065 -0.305054)
			(stroke
				(width 0.1)
				(type default)
			)
			(layer "F.Fab")
		)
		(fp_line
			(start 0.67945 -0.3048)
			(end 0.67945 0.3048)
			(stroke
				(width 0.1)
				(type default)
			)
			(layer "F.Fab")
		)
		(fp_line
			(start 0.12065 -0.3048)
			(end 0.67945 -0.3048)
			(stroke
				(width 0.1)
				(type default)
			)
			(layer "F.Fab")
		)
		(fp_line
			(start 0.12065 -0.2794)
			(end 0.12065 -0.3048)
			(stroke
				(width 0.1)
				(type default)
			)
			(layer "F.Fab")
		)
		(fp_line
			(start -0.12065 -0.2794)
			(end 0.12065 -0.2794)
			(stroke
				(width 0.1)
				(type default)
			)
			(layer "F.Fab")
		)
		(fp_line
			(start 0.120396 0.2794)
			(end -0.12065 0.2794)
			(stroke
				(width 0.1)
				(type default)
			)
			(layer "F.Fab")
		)
		(fp_line
			(start -0.12065 0.2794)
			(end -0.12065 0.3048)
			(stroke
				(width 0.1)
				(type default)
			)
			(layer "F.Fab")
		)
		(fp_line
			(start 0.67945 0.3048)
			(end 0.120396 0.3048)
			(stroke
				(width 0.1)
				(type default)
			)
			(layer "F.Fab")
		)
		(fp_line
			(start 0.120396 0.3048)
			(end 0.120396 0.2794)
			(stroke
				(width 0.1)
				(type default)
			)
			(layer "F.Fab")
		)
		(fp_line
			(start -0.12065 0.3048)
			(end -0.67945 0.3048)
			(stroke
				(width 0.1)
				(type default)
			)
			(layer "F.Fab")
		)
		(fp_line
			(start -0.67945 0.3048)
			(end -0.67945 -0.305054)
			(stroke
				(width 0.1)
				(type default)
			)
			(layer "F.Fab")
		)
		(pad "1" smd circle
			(at -0.40005 0 90)
			(size 0 0)
			(layers "F.Cu" "F.Mask" "F.Paste")
			(net "PVCCIN_CPU0")
		)
		(pad "2" smd circle
			(at 0.40005 0 90)
			(size 0 0)
			(layers "F.Cu" "F.Mask" "F.Paste")
			(net "GND")
		)
	)
	(footprint ""
		(layer "F.Cu")
		(at 9.58088 -52.923948)
		(property "Reference" "R3050"
			(at 0 0 0)
			(layer "F.SilkS")
			(hide yes)
			(effects
				(font
					(size 1.27 1.27)
				)
			)
		)
		(property "Value" ""
			(at 0 0 0)
			(layer "F.Fab")
			(effects
				(font
					(size 1.27 1.27)
				)
			)
		)
		(duplicate_pad_numbers_are_jumpers no)
		(fp_line
			(start -0.7874 -0.4064)
			(end 0.7874 -0.4064)
			(stroke
				(width 0.1524)
				(type default)
			)
			(layer "F.SilkS")
		)
		(fp_line
			(start -0.7874 0.4064)
			(end -0.7874 -0.4064)
			(stroke
				(width 0.1524)
				(type default)
			)
			(layer "F.SilkS")
		)
		(fp_line
			(start 0.7874 -0.4064)
			(end 0.7874 0.4064)
			(stroke
				(width 0.1524)
				(type default)
			)
			(layer "F.SilkS")
		)
		(fp_line
			(start 0.7874 0.4064)
			(end -0.7874 0.4064)
			(stroke
				(width 0.1524)
				(type default)
			)
			(layer "F.SilkS")
		)
		(fp_line
			(start -0.67945 -0.305054)
			(end -0.12065 -0.305054)
			(stroke
				(width 0.1)
				(type default)
			)
			(layer "F.Fab")
		)
		(fp_line
			(start -0.67945 0.3048)
			(end -0.67945 -0.305054)
			(stroke
				(width 0.1)
				(type default)
			)
			(layer "F.Fab")
		)
		(fp_line
			(start -0.12065 -0.305054)
			(end -0.12065 -0.2794)
			(stroke
				(width 0.1)
				(type default)
			)
			(layer "F.Fab")
		)
		(fp_line
			(start -0.12065 -0.2794)
			(end 0.12065 -0.2794)
			(stroke
				(width 0.1)
				(type default)
			)
			(layer "F.Fab")
		)
		(fp_line
			(start -0.12065 0.2794)
			(end -0.12065 0.3048)
			(stroke
				(width 0.1)
				(type default)
			)
			(layer "F.Fab")
		)
		(fp_line
			(start -0.12065 0.3048)
			(end -0.67945 0.3048)
			(stroke
				(width 0.1)
				(type default)
			)
			(layer "F.Fab")
		)
		(fp_line
			(start 0.120396 0.2794)
			(end -0.12065 0.2794)
			(stroke
				(width 0.1)
				(type default)
			)
			(layer "F.Fab")
		)
		(fp_line
			(start 0.120396 0.3048)
			(end 0.120396 0.2794)
			(stroke
				(width 0.1)
				(type default)
			)
			(layer "F.Fab")
		)
		(fp_line
			(start 0.12065 -0.3048)
			(end 0.67945 -0.3048)
			(stroke
				(width 0.1)
				(type default)
			)
			(layer "F.Fab")
		)
		(fp_line
			(start 0.12065 -0.2794)
			(end 0.12065 -0.3048)
			(stroke
				(width 0.1)
				(type default)
			)
			(layer "F.Fab")
		)
		(fp_line
			(start 0.67945 -0.3048)
			(end 0.67945 0.3048)
			(stroke
				(width 0.1)
				(type default)
			)
			(layer "F.Fab")
		)
		(fp_line
			(start 0.67945 0.3048)
			(end 0.120396 0.3048)
			(stroke
				(width 0.1)
				(type default)
			)
			(layer "F.Fab")
		)
		(pad "1" smd circle
			(at -0.40005 0)
			(size 0 0)
			(layers "F.Cu" "F.Mask" "F.Paste")
			(net "RST_RSMRST_PLD_R_N")
		)
		(pad "2" smd circle
			(at 0.40005 0)
			(size 0 0)
			(layers "F.Cu" "F.Mask" "F.Paste")
			(net "RST_RSMRST_NM_HDR_N")
		)
	)
	(footprint ""
		(layer "F.Cu")
		(at 463.636106 -110.287308 180)
		(property "Reference" "R1150"
			(at 0 0 180)
			(layer "F.SilkS")
			(hide yes)
			(effects
				(font
					(size 1.27 1.27)
				)
			)
		)
		(property "Value" ""
			(at 0 0 180)
			(layer "F.Fab")
			(effects
				(font
					(size 1.27 1.27)
				)
			)
		)
		(duplicate_pad_numbers_are_jumpers no)
		(fp_line
			(start 0.7874 0.4064)
			(end -0.7874 0.4064)
			(stroke
				(width 0.1524)
				(type default)
			)
			(layer "F.SilkS")
		)
		(fp_line
			(start 0.7874 -0.4064)
			(end 0.7874 0.4064)
			(stroke
				(width 0.1524)
				(type default)
			)
			(layer "F.SilkS")
		)
		(fp_line
			(start -0.7874 0.4064)
			(end -0.7874 -0.4064)
			(stroke
				(width 0.1524)
				(type default)
			)
			(layer "F.SilkS")
		)
		(fp_line
			(start -0.7874 -0.4064)
			(end 0.7874 -0.4064)
			(stroke
				(width 0.1524)
				(type default)
			)
			(layer "F.SilkS")
		)
		(fp_line
			(start 0.67945 0.3048)
			(end 0.120396 0.3048)
			(stroke
				(width 0.1)
				(type default)
			)
			(layer "F.Fab")
		)
		(fp_line
			(start 0.67945 -0.3048)
			(end 0.67945 0.3048)
			(stroke
				(width 0.1)
				(type default)
			)
			(layer "F.Fab")
		)
		(fp_line
			(start 0.12065 -0.2794)
			(end 0.12065 -0.3048)
			(stroke
				(width 0.1)
				(type default)
			)
			(layer "F.Fab")
		)
		(fp_line
			(start 0.12065 -0.3048)
			(end 0.67945 -0.3048)
			(stroke
				(width 0.1)
				(type default)
			)
			(layer "F.Fab")
		)
		(fp_line
			(start 0.120396 0.3048)
			(end 0.120396 0.2794)
			(stroke
				(width 0.1)
				(type default)
			)
			(layer "F.Fab")
		)
		(fp_line
			(start 0.120396 0.2794)
			(end -0.12065 0.2794)
			(stroke
				(width 0.1)
				(type default)
			)
			(layer "F.Fab")
		)
		(fp_line
			(start -0.12065 0.3048)
			(end -0.67945 0.3048)
			(stroke
				(width 0.1)
				(type default)
			)
			(layer "F.Fab")
		)
		(fp_line
			(start -0.12065 0.2794)
			(end -0.12065 0.3048)
			(stroke
				(width 0.1)
				(type default)
			)
			(layer "F.Fab")
		)
		(fp_line
			(start -0.12065 -0.2794)
			(end 0.12065 -0.2794)
			(stroke
				(width 0.1)
				(type default)
			)
			(layer "F.Fab")
		)
		(fp_line
			(start -0.12065 -0.305054)
			(end -0.12065 -0.2794)
			(stroke
				(width 0.1)
				(type default)
			)
			(layer "F.Fab")
		)
		(fp_line
			(start -0.67945 0.3048)
			(end -0.67945 -0.305054)
			(stroke
				(width 0.1)
				(type default)
			)
			(layer "F.Fab")
		)
		(fp_line
			(start -0.67945 -0.305054)
			(end -0.12065 -0.305054)
			(stroke
				(width 0.1)
				(type default)
			)
			(layer "F.Fab")
		)
		(pad "1" smd circle
			(at -0.40005 0 180)
			(size 0 0)
			(layers "F.Cu" "F.Mask" "F.Paste")
			(net "P3V3_AUX")
		)
		(pad "2" smd circle
			(at 0.40005 0 180)
			(size 0 0)
			(layers "F.Cu" "F.Mask" "F.Paste")
			(net "HP_LVC3_OCP_V3_1_PRSNT2_N")
		)
	)
	(footprint ""
		(layer "F.Cu")
		(at 165.47846 -56.820308 90)
		(property "Reference" "C1920"
			(at 0 0 90)
			(layer "F.SilkS")
			(hide yes)
			(effects
				(font
					(size 1.27 1.27)
				)
			)
		)
		(property "Value" ""
			(at 0 0 90)
			(layer "F.Fab")
			(effects
				(font
					(size 1.27 1.27)
				)
			)
		)
		(duplicate_pad_numbers_are_jumpers no)
		(fp_line
			(start 1.2954 -0.5842)
			(end 1.2954 0.5842)
			(stroke
				(width 0.1524)
				(type default)
			)
			(layer "F.SilkS")
		)
		(fp_line
			(start 0 -0.5842)
			(end 0 0.5842)
			(stroke
				(width 0.1524)
				(type default)
			)
			(layer "F.SilkS")
		)
		(fp_line
			(start -1.2954 -0.5842)
			(end 1.2954 -0.5842)
			(stroke
				(width 0.1524)
				(type default)
			)
			(layer "F.SilkS")
		)
		(fp_line
			(start 1.2954 0.5842)
			(end -1.2954 0.5842)
			(stroke
				(width 0.1524)
				(type default)
			)
			(layer "F.SilkS")
		)
		(fp_line
			(start -1.2954 0.5842)
			(end -1.2954 -0.5842)
			(stroke
				(width 0.1524)
				(type default)
			)
			(layer "F.SilkS")
		)
		(fp_line
			(start 0.8636 -0.4572)
			(end 0.8636 -0.4064)
			(stroke
				(width 0.1)
				(type default)
			)
			(layer "F.Fab")
		)
		(fp_line
			(start -0.8636 -0.4572)
			(end 0.8636 -0.4572)
			(stroke
				(width 0.1)
				(type default)
			)
			(layer "F.Fab")
		)
		(fp_line
			(start 1.1938 -0.4064)
			(end 1.1938 0.4064)
			(stroke
				(width 0.1)
				(type default)
			)
			(layer "F.Fab")
		)
		(fp_line
			(start 0.8636 -0.4064)
			(end 1.1938 -0.4064)
			(stroke
				(width 0.1)
				(type default)
			)
			(layer "F.Fab")
		)
		(fp_line
			(start -0.8636 -0.4064)
			(end -0.8636 -0.4572)
			(stroke
				(width 0.1)
				(type default)
			)
			(layer "F.Fab")
		)
		(fp_line
			(start -1.1938 -0.4064)
			(end -0.8636 -0.4064)
			(stroke
				(width 0.1)
				(type default)
			)
			(layer "F.Fab")
		)
		(fp_line
			(start 1.1938 0.4064)
			(end 0.8636 0.4064)
			(stroke
				(width 0.1)
				(type default)
			)
			(layer "F.Fab")
		)
		(fp_line
			(start 0.8636 0.4064)
			(end 0.8636 0.4572)
			(stroke
				(width 0.1)
				(type default)
			)
			(layer "F.Fab")
		)
		(fp_line
			(start -0.8636 0.4064)
			(end -1.1938 0.4064)
			(stroke
				(width 0.1)
				(type default)
			)
			(layer "F.Fab")
		)
		(fp_line
			(start -1.1938 0.4064)
			(end -1.1938 -0.4064)
			(stroke
				(width 0.1)
				(type default)
			)
			(layer "F.Fab")
		)
		(fp_line
			(start 0.8636 0.4572)
			(end -0.8636 0.4572)
			(stroke
				(width 0.1)
				(type default)
			)
			(layer "F.Fab")
		)
		(fp_line
			(start -0.8636 0.4572)
			(end -0.8636 0.4064)
			(stroke
				(width 0.1)
				(type default)
			)
			(layer "F.Fab")
		)
		(pad "1" smd rect
			(at -0.7366 0)
			(size 0.7112 0.8128)
			(layers "F.Cu" "F.Mask" "F.Paste")
			(net "P3V3_M2_0")
		)
		(pad "2" smd rect
			(at 0.7366 0)
			(size 0.7112 0.8128)
			(layers "F.Cu" "F.Mask" "F.Paste")
			(net "GND")
		)
	)
	(footprint ""
		(layer "F.Cu")
		(at 70.743318 -408.517344 -90)
		(property "Reference" "C694"
			(at 0 0 270)
			(layer "F.SilkS")
			(hide yes)
			(effects
				(font
					(size 1.27 1.27)
				)
			)
		)
		(property "Value" ""
			(at 0 0 270)
			(layer "F.Fab")
			(effects
				(font
					(size 1.27 1.27)
				)
			)
		)
		(duplicate_pad_numbers_are_jumpers no)
		(fp_line
			(start -0.299974 0.150114)
			(end -0.299974 -0.150114)
			(stroke
				(width 0.1)
				(type default)
			)
			(layer "F.Fab")
		)
		(fp_line
			(start 0.299974 0.150114)
			(end -0.299974 0.150114)
			(stroke
				(width 0.1)
				(type default)
			)
			(layer "F.Fab")
		)
		(fp_line
			(start -0.299974 -0.150114)
			(end 0.299974 -0.150114)
			(stroke
				(width 0.1)
				(type default)
			)
			(layer "F.Fab")
		)
		(fp_line
			(start 0.299974 -0.150114)
			(end 0.299974 0.150114)
			(stroke
				(width 0.1)
				(type default)
			)
			(layer "F.Fab")
		)
		(pad "1" smd rect
			(at -0.2667 0 270)
			(size 0.3048 0.381)
			(layers "F.Cu" "F.Mask" "F.Paste")
			(net "P5E_CPU1_PE4_TX_C_DN<7>")
		)
		(pad "2" smd rect
			(at 0.2667 0 270)
			(size 0.3048 0.381)
			(layers "F.Cu" "F.Mask" "F.Paste")
			(net "P5E_CPU1_PE4_TX_DN<7>")
		)
	)
	(footprint ""
		(layer "F.Cu")
		(at 126.91872 -22.172168 90)
		(property "Reference" "L18"
			(at 0 0 90)
			(layer "F.SilkS")
			(hide yes)
			(effects
				(font
					(size 1.27 1.27)
				)
			)
		)
		(property "Value" ""
			(at 0 0 90)
			(layer "F.Fab")
			(effects
				(font
					(size 1.27 1.27)
				)
			)
		)
		(duplicate_pad_numbers_are_jumpers no)
		(fp_line
			(start 0.762 -0.381)
			(end 0.762 0.381)
			(stroke
				(width 0.1524)
				(type default)
			)
			(layer "F.SilkS")
		)
		(fp_line
			(start -0.762 -0.381)
			(end 0.762 -0.381)
			(stroke
				(width 0.1524)
				(type default)
			)
			(layer "F.SilkS")
		)
		(fp_line
			(start 0.762 0.381)
			(end -0.762 0.381)
			(stroke
				(width 0.1524)
				(type default)
			)
			(layer "F.SilkS")
		)
		(fp_line
			(start -0.762 0.381)
			(end -0.762 -0.381)
			(stroke
				(width 0.1524)
				(type default)
			)
			(layer "F.SilkS")
		)
		(fp_line
			(start -0.118364 -0.307086)
			(end -0.118364 -0.2794)
			(stroke
				(width 0.1)
				(type default)
			)
			(layer "F.Fab")
		)
		(fp_line
			(start -0.681736 -0.307086)
			(end -0.118364 -0.307086)
			(stroke
				(width 0.1)
				(type default)
			)
			(layer "F.Fab")
		)
		(fp_line
			(start 0.680466 -0.306324)
			(end 0.680466 0.306324)
			(stroke
				(width 0.1)
				(type default)
			)
			(layer "F.Fab")
		)
		(fp_line
			(start 0.118872 -0.306324)
			(end 0.680466 -0.306324)
			(stroke
				(width 0.1)
				(type default)
			)
			(layer "F.Fab")
		)
		(fp_line
			(start 0.118872 -0.2794)
			(end 0.118872 -0.306324)
			(stroke
				(width 0.1)
				(type default)
			)
			(layer "F.Fab")
		)
		(fp_line
			(start -0.118364 -0.2794)
			(end 0.118872 -0.2794)
			(stroke
				(width 0.1)
				(type default)
			)
			(layer "F.Fab")
		)
		(fp_line
			(start 0.118364 0.2794)
			(end -0.119634 0.2794)
			(stroke
				(width 0.1)
				(type default)
			)
			(layer "F.Fab")
		)
		(fp_line
			(start -0.119634 0.2794)
			(end -0.119634 0.30607)
			(stroke
				(width 0.1)
				(type default)
			)
			(layer "F.Fab")
		)
		(fp_line
			(start -0.119634 0.30607)
			(end -0.681736 0.30607)
			(stroke
				(width 0.1)
				(type default)
			)
			(layer "F.Fab")
		)
		(fp_line
			(start -0.681736 0.30607)
			(end -0.681736 -0.307086)
			(stroke
				(width 0.1)
				(type default)
			)
			(layer "F.Fab")
		)
		(fp_line
			(start 0.680466 0.306324)
			(end 0.118364 0.306324)
			(stroke
				(width 0.1)
				(type default)
			)
			(layer "F.Fab")
		)
		(fp_line
			(start 0.118364 0.306324)
			(end 0.118364 0.2794)
			(stroke
				(width 0.1)
				(type default)
			)
			(layer "F.Fab")
		)
		(pad "1" smd rect
			(at -0.40005 0 270)
			(size 0.4572 0.508)
			(layers "F.Cu" "F.Mask" "F.Paste")
			(net "P3V3_AUX")
		)
		(pad "2" smd rect
			(at 0.40005 0 270)
			(size 0.4572 0.508)
			(layers "F.Cu" "F.Mask" "F.Paste")
			(net "P3V3_AUX_USB_BUF")
		)
	)
	(footprint ""
		(layer "F.Cu")
		(at 54.080918 -402.371052 -90)
		(property "Reference" "C714"
			(at 0 0 270)
			(layer "F.SilkS")
			(hide yes)
			(effects
				(font
					(size 1.27 1.27)
				)
			)
		)
		(property "Value" ""
			(at 0 0 270)
			(layer "F.Fab")
			(effects
				(font
					(size 1.27 1.27)
				)
			)
		)
		(duplicate_pad_numbers_are_jumpers no)
		(fp_line
			(start -0.299974 0.150114)
			(end -0.299974 -0.150114)
			(stroke
				(width 0.1)
				(type default)
			)
			(layer "F.Fab")
		)
		(fp_line
			(start 0.299974 0.150114)
			(end -0.299974 0.150114)
			(stroke
				(width 0.1)
				(type default)
			)
			(layer "F.Fab")
		)
		(fp_line
			(start -0.299974 -0.150114)
			(end 0.299974 -0.150114)
			(stroke
				(width 0.1)
				(type default)
			)
			(layer "F.Fab")
		)
		(fp_line
			(start 0.299974 -0.150114)
			(end 0.299974 0.150114)
			(stroke
				(width 0.1)
				(type default)
			)
			(layer "F.Fab")
		)
		(pad "1" smd rect
			(at -0.2667 0 270)
			(size 0.3048 0.381)
			(layers "F.Cu" "F.Mask" "F.Paste")
			(net "P5E_CPU1_PE0_TX_C_DN<13>")
		)
		(pad "2" smd rect
			(at 0.2667 0 270)
			(size 0.3048 0.381)
			(layers "F.Cu" "F.Mask" "F.Paste")
			(net "P5E_CPU1_PE0_TX_DN<13>")
		)
	)
)
